# S9S_MB_2U (Grand Teton) — schematic netlist excerpt (pin names and nets, part order shuffled) for the footprints in the layout excerpt that follows; sources: Cadence DE-HDL packaged netlist, KiCad conversion of 03242023_DA0F0TMBIJ0_F0T_Motherboard_J_brd_V01_OCP.brd

R1233  Q_RES  240 1% EMPTY  pkg 0402LF  page 119 : A = PVNN_TERM_CPU0 ; B = PUD_XTAL_CPU0_MODE1
R758  Q_RES  150 1% CHIP  pkg 0402LF  page 132 : A = PVNN_TERM_CPU0 ; B = H_CPU_PREQ_QS_GTL_N

(kicad_pcb
	(version 20260206)
	(generator "pcbnew")
	(generator_version "10.0")
	(general
		(thickness 1.6)
		(legacy_teardrops no)
	)
	(paper "A4")
	(title_block
		(title "03242023_DA0F0TMBIJ0_F0T_Motherboard_J_brd_V01_OCP.brd")
		(comment 1 "Grand Teton / footprints 5284-5285 of 6105")
	)
	(layers
		(0 "F.Cu" signal "TOP")
		(4 "In1.Cu" signal "GND")
		(6 "In2.Cu" signal "IN1")
		(8 "In3.Cu" signal "GND1")
		(10 "In4.Cu" signal "IN2")
		(12 "In5.Cu" signal "GND2")
		(14 "In6.Cu" signal "IN3")
		(16 "In7.Cu" signal "GND3")
		(18 "In8.Cu" signal "VCC")
		(20 "In9.Cu" signal "VCC1")
		(22 "In10.Cu" signal "GND4")
		(24 "In11.Cu" signal "IN4")
		(26 "In12.Cu" signal "GND5")
		(28 "In13.Cu" signal "IN5")
		(30 "In14.Cu" signal "GND6")
		(32 "In15.Cu" signal "IN6")
		(34 "In16.Cu" signal "GND7")
		(2 "B.Cu" signal "BOTTOM")
		(9 "F.Adhes" user "F.Adhesive")
		(11 "B.Adhes" user "B.Adhesive")
		(13 "F.Paste" user "Package Geometry/Pastemask Top")
		(15 "B.Paste" user "Package Geometry/Pastemask Bottom")
		(5 "F.SilkS" user "Ref Des/Silkscreen Top")
		(7 "B.SilkS" user "Ref Des/Silkscreen Bottom")
		(1 "F.Mask" user "Board Geometry/Soldermask Top")
		(3 "B.Mask" user "Board Geometry/Soldermask Bottom")
		(17 "Dwgs.User" user "User.Drawings")
		(19 "Cmts.User" user "User.Comments")
		(21 "Eco1.User" user "User.Eco1")
		(23 "Eco2.User" user "User.Eco2")
		(25 "Edge.Cuts" user "Board Geometry/Outline")
		(27 "Margin" user)
		(31 "F.CrtYd" user "Package Geometry/Place Bound Top")
		(29 "B.CrtYd" user "Package Geometry/Place Bound Bottom")
		(35 "F.Fab" user "Ref Des/Assembly Top")
		(33 "B.Fab" user "Ref Des/Assembly Bottom")
	)
	(footprint ""
		(layer "B.Cu")
		(at 404.09241 -193.05143 -90)
		(property "Reference" "R1233"
			(at 0 0 90)
			(layer "B.SilkS")
			(hide yes)
			(effects
				(font
					(size 1.27 1.27)
				)
				(justify mirror)
			)
		)
		(property "Value" ""
			(at 0 0 90)
			(layer "B.Fab")
			(effects
				(font
					(size 1.27 1.27)
				)
				(justify mirror)
			)
		)
		(duplicate_pad_numbers_are_jumpers no)
		(fp_line
			(start -0.7874 0.4064)
			(end 0.7874 0.4064)
			(stroke
				(width 0.1524)
				(type default)
			)
			(layer "B.SilkS")
		)
		(fp_line
			(start 0.7874 0.4064)
			(end 0.7874 -0.4064)
			(stroke
				(width 0.1524)
				(type default)
			)
			(layer "B.SilkS")
		)
		(fp_line
			(start -0.7874 -0.4064)
			(end -0.7874 0.4064)
			(stroke
				(width 0.1524)
				(type default)
			)
			(layer "B.SilkS")
		)
		(fp_line
			(start 0.7874 -0.4064)
			(end -0.7874 -0.4064)
			(stroke
				(width 0.1524)
				(type default)
			)
			(layer "B.SilkS")
		)
		(fp_line
			(start -0.67945 0.3048)
			(end -0.120396 0.3048)
			(stroke
				(width 0.1)
				(type default)
			)
			(layer "B.Fab")
		)
		(fp_line
			(start -0.120396 0.3048)
			(end -0.120396 0.2794)
			(stroke
				(width 0.1)
				(type default)
			)
			(layer "B.Fab")
		)
		(fp_line
			(start 0.12065 0.3048)
			(end 0.67945 0.3048)
			(stroke
				(width 0.1)
				(type default)
			)
			(layer "B.Fab")
		)
		(fp_line
			(start 0.67945 0.3048)
			(end 0.67945 -0.305054)
			(stroke
				(width 0.1)
				(type default)
			)
			(layer "B.Fab")
		)
		(fp_line
			(start -0.120396 0.2794)
			(end 0.12065 0.2794)
			(stroke
				(width 0.1)
				(type default)
			)
			(layer "B.Fab")
		)
		(fp_line
			(start 0.12065 0.2794)
			(end 0.12065 0.3048)
			(stroke
				(width 0.1)
				(type default)
			)
			(layer "B.Fab")
		)
		(fp_line
			(start -0.12065 -0.2794)
			(end -0.12065 -0.3048)
			(stroke
				(width 0.1)
				(type default)
			)
			(layer "B.Fab")
		)
		(fp_line
			(start 0.12065 -0.2794)
			(end -0.12065 -0.2794)
			(stroke
				(width 0.1)
				(type default)
			)
			(layer "B.Fab")
		)
		(fp_line
			(start -0.67945 -0.3048)
			(end -0.67945 0.3048)
			(stroke
				(width 0.1)
				(type default)
			)
			(layer "B.Fab")
		)
		(fp_line
			(start -0.12065 -0.3048)
			(end -0.67945 -0.3048)
			(stroke
				(width 0.1)
				(type default)
			)
			(layer "B.Fab")
		)
		(fp_line
			(start 0.12065 -0.305054)
			(end 0.12065 -0.2794)
			(stroke
				(width 0.1)
				(type default)
			)
			(layer "B.Fab")
		)
		(fp_line
			(start 0.67945 -0.305054)
			(end 0.12065 -0.305054)
			(stroke
				(width 0.1)
				(type default)
			)
			(layer "B.Fab")
		)
		(pad "1" smd circle
			(at 0.40005 0 90)
			(size 0 0)
			(layers "B.Cu" "B.Mask" "B.Paste")
			(net "PVNN_TERM_CPU0")
		)
		(pad "2" smd circle
			(at -0.40005 0 90)
			(size 0 0)
			(layers "B.Cu" "B.Mask" "B.Paste")
			(net "PUD_XTAL_CPU0_MODE1")
		)
	)
	(footprint ""
		(layer "B.Cu")
		(at 76.463652 -181.65699 -90)
		(property "Reference" "R758"
			(at 0 0 90)
			(layer "B.SilkS")
			(hide yes)
			(effects
				(font
					(size 1.27 1.27)
				)
				(justify mirror)
			)
		)
		(property "Value" ""
			(at 0 0 90)
			(layer "B.Fab")
			(effects
				(font
					(size 1.27 1.27)
				)
				(justify mirror)
			)
		)
		(duplicate_pad_numbers_are_jumpers no)
		(fp_line
			(start -0.7874 0.4064)
			(end 0.7874 0.4064)
			(stroke
				(width 0.1524)
				(type default)
			)
			(layer "B.SilkS")
		)
		(fp_line
			(start 0.7874 0.4064)
			(end 0.7874 -0.4064)
			(stroke
				(width 0.1524)
				(type default)
			)
			(layer "B.SilkS")
		)
		(fp_line
			(start -0.7874 -0.4064)
			(end -0.7874 0.4064)
			(stroke
				(width 0.1524)
				(type default)
			)
			(layer "B.SilkS")
		)
		(fp_line
			(start 0.7874 -0.4064)
			(end -0.7874 -0.4064)
			(stroke
				(width 0.1524)
				(type default)
			)
			(layer "B.SilkS")
		)
		(fp_line
			(start -0.67945 0.3048)
			(end -0.120396 0.3048)
			(stroke
				(width 0.1)
				(type default)
			)
			(layer "B.Fab")
		)
		(fp_line
			(start -0.120396 0.3048)
			(end -0.120396 0.2794)
			(stroke
				(width 0.1)
				(type default)
			)
			(layer "B.Fab")
		)
		(fp_line
			(start 0.12065 0.3048)
			(end 0.67945 0.3048)
			(stroke
				(width 0.1)
				(type default)
			)
			(layer "B.Fab")
		)
		(fp_line
			(start 0.67945 0.3048)
			(end 0.67945 -0.305054)
			(stroke
				(width 0.1)
				(type default)
			)
			(layer "B.Fab")
		)
		(fp_line
			(start -0.120396 0.2794)
			(end 0.12065 0.2794)
			(stroke
				(width 0.1)
				(type default)
			)
			(layer "B.Fab")
		)
		(fp_line
			(start 0.12065 0.2794)
			(end 0.12065 0.3048)
			(stroke
				(width 0.1)
				(type default)
			)
			(layer "B.Fab")
		)
		(fp_line
			(start -0.12065 -0.2794)
			(end -0.12065 -0.3048)
			(stroke
				(width 0.1)
				(type default)
			)
			(layer "B.Fab")
		)
		(fp_line
			(start 0.12065 -0.2794)
			(end -0.12065 -0.2794)
			(stroke
				(width 0.1)
				(type default)
			)
			(layer "B.Fab")
		)
		(fp_line
			(start -0.67945 -0.3048)
			(end -0.67945 0.3048)
			(stroke
				(width 0.1)
				(type default)
			)
			(layer "B.Fab")
		)
		(fp_line
			(start -0.12065 -0.3048)
			(end -0.67945 -0.3048)
			(stroke
				(width 0.1)
				(type default)
			)
			(layer "B.Fab")
		)
		(fp_line
			(start 0.12065 -0.305054)
			(end 0.12065 -0.2794)
			(stroke
				(width 0.1)
				(type default)
			)
			(layer "B.Fab")
		)
		(fp_line
			(start 0.67945 -0.305054)
			(end 0.12065 -0.305054)
			(stroke
				(width 0.1)
				(type default)
			)
			(layer "B.Fab")
		)
		(pad "1" smd circle
			(at 0.40005 0 90)
			(size 0 0)
			(layers "B.Cu" "B.Mask" "B.Paste")
			(net "PVNN_TERM_CPU0")
		)
		(pad "2" smd circle
			(at -0.40005 0 90)
			(size 0 0)
			(layers "B.Cu" "B.Mask" "B.Paste")
			(net "H_CPU_PREQ_QS_GTL_N")
		)
	)
)
